(kicad_pcb
	(version 20260206)
	(generator "pcbnew")
	(generator_version "10.0")
	(general
		(thickness 1.6)
		(legacy_teardrops no)
	)
	(paper "A4")
	(title_block
		(title "04192023_DAF0TMB3IC0_F0TG_MB_C_brd_V02_OCP.brd")
		(comment 1 "Grand Teton / footprints 6186-6192 of 8354")
	)
	(layers
		(0 "F.Cu" signal "TOP")
		(4 "In1.Cu" signal "GND")
		(6 "In2.Cu" signal "IN1")
		(8 "In3.Cu" signal "GND1")
		(10 "In4.Cu" signal "IN2")
		(12 "In5.Cu" signal "GND2")
		(14 "In6.Cu" signal "IN3")
		(16 "In7.Cu" signal "GND3")
		(18 "In8.Cu" signal "VCC")
		(20 "In9.Cu" signal "VCC1")
		(22 "In10.Cu" signal "GND4")
		(24 "In11.Cu" signal "IN4")
		(26 "In12.Cu" signal "GND5")
		(28 "In13.Cu" signal "IN5")
		(30 "In14.Cu" signal "GND6")
		(32 "In15.Cu" signal "IN6")
		(34 "In16.Cu" signal "GND7")
		(2 "B.Cu" signal "BOTTOM")
		(9 "F.Adhes" user "F.Adhesive")
		(11 "B.Adhes" user "B.Adhesive")
		(13 "F.Paste" user "Package Geometry/Pastemask Top")
		(15 "B.Paste" user "Package Geometry/Pastemask Bottom")
		(5 "F.SilkS" user "Ref Des/Silkscreen Top")
		(7 "B.SilkS" user "Ref Des/Silkscreen Bottom")
		(1 "F.Mask" user "Board Geometry/Soldermask Top")
		(3 "B.Mask" user "Board Geometry/Soldermask Bottom")
		(17 "Dwgs.User" user "User.Drawings")
		(19 "Cmts.User" user "User.Comments")
		(21 "Eco1.User" user "User.Eco1")
		(23 "Eco2.User" user "User.Eco2")
		(25 "Edge.Cuts" user "Board Geometry/Outline")
		(27 "Margin" user)
		(31 "F.CrtYd" user "Package Geometry/Place Bound Top")
		(29 "B.CrtYd" user "Package Geometry/Place Bound Bottom")
		(35 "F.Fab" user "Ref Des/Assembly Top")
		(33 "B.Fab" user "Ref Des/Assembly Bottom")
	)
	(footprint ""
		(layer "B.Cu")
		(at 485.20985 -142.805658 -90)
		(property "Reference" "X8012"
			(at 4.4577 -1.50495 270)
			(unlocked yes)
			(layer "B.SilkS")
			(effects
				(font
					(size 0.7874 0.5842)
					(thickness 0.1524)
				)
				(justify left mirror)
			)
		)
		(property "Value" ""
			(at 0 0 90)
			(layer "B.Fab")
			(effects
				(font
					(size 1.27 1.27)
				)
				(justify mirror)
			)
		)
		(property "Device Type" "TP_TDR_4P_FTS_TH-TP_TDR_4P_DIP,EMPTY,TP15"
			(at -1.30175 1.27 180)
			(unlocked yes)
			(layer "B.Fab")
			(hide yes)
			(effects
				(font
					(size 0.635 0.4064)
					(thickness 0.1524)
				)
				(justify mirror)
			)
		)
		(property "User Part Number" "N_A"
			(at -1.30175 1.27 180)
			(unlocked yes)
			(layer "Cmts.User")
			(hide yes)
			(effects
				(font
					(size 0.635 0.4064)
					(thickness 0.1524)
				)
				(justify mirror)
			)
		)
		(duplicate_pad_numbers_are_jumpers no)
		(fp_line
			(start -2.54 3.81)
			(end -2.54 3.6703)
			(stroke
				(width 0.1524)
				(type default)
			)
			(layer "B.SilkS")
		)
		(fp_line
			(start 0 3.81)
			(end -2.54 3.81)
			(stroke
				(width 0.1524)
				(type default)
			)
			(layer "B.SilkS")
		)
		(fp_line
			(start 0 3.175)
			(end 0 3.81)
			(stroke
				(width 0.1524)
				(type default)
			)
			(layer "B.SilkS")
		)
		(fp_line
			(start -2.54 1.4097)
			(end -2.54 1.1303)
			(stroke
				(width 0.1524)
				(type default)
			)
			(layer "B.SilkS")
		)
		(fp_line
			(start 0 0.635)
			(end 0 1.905)
			(stroke
				(width 0.1524)
				(type default)
			)
			(layer "B.SilkS")
		)
		(fp_line
			(start -2.54 -1.1303)
			(end -2.54 -1.27)
			(stroke
				(width 0.1524)
				(type default)
			)
			(layer "B.SilkS")
		)
		(fp_line
			(start -2.54 -1.27)
			(end 0 -1.27)
			(stroke
				(width 0.1524)
				(type default)
			)
			(layer "B.SilkS")
		)
		(fp_line
			(start 0 -1.27)
			(end 0 -0.635)
			(stroke
				(width 0.1524)
				(type default)
			)
			(layer "B.SilkS")
		)
		(fp_poly
			(pts
				(xy 0.761746 0) (xy 2.285746 -0.762) (xy 2.285746 0.762)
			)
			(stroke
				(width 0)
				(type default)
			)
			(fill yes)
			(layer "B.SilkS")
		)
		(fp_line
			(start -2.54 3.81)
			(end -2.54 -1.27)
			(stroke
				(width 0.1)
				(type default)
			)
			(layer "B.Fab")
		)
		(fp_line
			(start 0 3.81)
			(end -2.54 3.81)
			(stroke
				(width 0.1)
				(type default)
			)
			(layer "B.Fab")
		)
		(fp_line
			(start -2.54 -1.27)
			(end 0 -1.27)
			(stroke
				(width 0.1)
				(type default)
			)
			(layer "B.Fab")
		)
		(fp_line
			(start 0 -1.27)
			(end 0 3.81)
			(stroke
				(width 0.1)
				(type default)
			)
			(layer "B.Fab")
		)
		(fp_poly
			(pts
				(xy 0.761746 0) (xy 2.285746 -0.762) (xy 2.285746 0.762)
			)
			(stroke
				(width 0)
				(type default)
			)
			(fill yes)
			(layer "B.Fab")
		)
		(pad "1" thru_hole circle
			(at 0 0 90)
			(size 1.0033 1.0033)
			(drill 0.249936)
			(layers "*.Cu" "*.Mask")
			(remove_unused_layers no)
			(net "TDR_DIFF_85_BOT_DN")
			(clearance 0.10795)
			(padstack
				(mode front_inner_back)
				(layer "Inner"
					(shape circle)
					(size 0.8001 0.8001)
					(clearance 0.1524)
				)
				(layer "B.Cu"
					(shape circle)
					(size 1.0033 1.0033)
					(thermal_gap 0.10795)
					(clearance 0.10795)
				)
			)
		)
		(pad "2" thru_hole circle
			(at -2.54 0 90)
			(size 1.9939 1.9939)
			(drill 0.249936)
			(layers "*.Cu" "*.Mask")
			(remove_unused_layers no)
			(net "T1_GND")
			(clearance 0.10795)
			(padstack
				(mode front_inner_back)
				(layer "Inner"
					(shape circle)
					(size 0.8001 0.8001)
					(clearance 0.1524)
				)
				(layer "B.Cu"
					(shape circle)
					(size 1.9939 1.9939)
					(thermal_gap 0.10795)
					(clearance 0.10795)
				)
			)
		)
		(pad "3" thru_hole circle
			(at -2.54 2.54 90)
			(size 1.9939 1.9939)
			(drill 0.249936)
			(layers "*.Cu" "*.Mask")
			(remove_unused_layers no)
			(net "T1_GND")
			(clearance 0.10795)
			(padstack
				(mode front_inner_back)
				(layer "Inner"
					(shape circle)
					(size 0.8001 0.8001)
					(clearance 0.1524)
				)
				(layer "B.Cu"
					(shape circle)
					(size 1.9939 1.9939)
					(thermal_gap 0.10795)
					(clearance 0.10795)
				)
			)
		)
		(pad "4" thru_hole circle
			(at 0 2.54 90)
			(size 1.0033 1.0033)
			(drill 0.249936)
			(layers "*.Cu" "*.Mask")
			(remove_unused_layers no)
			(net "TDR_DIFF_85_BOT_DP")
			(clearance 0.10795)
			(padstack
				(mode front_inner_back)
				(layer "Inner"
					(shape circle)
					(size 0.8001 0.8001)
					(clearance 0.1524)
				)
				(layer "B.Cu"
					(shape circle)
					(size 1.0033 1.0033)
					(thermal_gap 0.10795)
					(clearance 0.10795)
				)
			)
		)
	)
	(footprint ""
		(layer "B.Cu")
		(at 94.49562 -381.11303)
		(property "Reference" "C7023"
			(at 2.6416 2.989072 0)
			(unlocked yes)
			(layer "B.SilkS")
			(effects
				(font
					(size 0.7874 0.5842)
					(thickness 0.1524)
				)
				(justify left mirror)
			)
		)
		(property "Value" ""
			(at 0 0 0)
			(layer "B.Fab")
			(effects
				(font
					(size 1.27 1.27)
				)
				(justify mirror)
			)
		)
		(duplicate_pad_numbers_are_jumpers no)
		(fp_line
			(start -4.53898 -2.15011)
			(end -4.53898 2.15011)
			(stroke
				(width 0.1524)
				(type default)
			)
			(layer "B.SilkS")
		)
		(fp_line
			(start -4.53898 2.15011)
			(end 4.53898 2.15011)
			(stroke
				(width 0.1524)
				(type default)
			)
			(layer "B.SilkS")
		)
		(fp_line
			(start 4.53898 -2.150618)
			(end 4.539742 2.152142)
			(stroke
				(width 0.1524)
				(type default)
			)
			(layer "B.SilkS")
		)
		(fp_line
			(start 4.53898 -2.15011)
			(end -4.53898 -2.15011)
			(stroke
				(width 0.1524)
				(type default)
			)
			(layer "B.SilkS")
		)
		(fp_line
			(start 4.53898 2.15011)
			(end 4.53898 -2.15011)
			(stroke
				(width 0.1524)
				(type default)
			)
			(layer "B.SilkS")
		)
		(fp_line
			(start 4.69138 -2.150618)
			(end 4.692396 2.161032)
			(stroke
				(width 0.1524)
				(type default)
			)
			(layer "B.SilkS")
		)
		(fp_line
			(start 4.83108 2.150364)
			(end 4.447794 2.149348)
			(stroke
				(width 0.1524)
				(type default)
			)
			(layer "B.SilkS")
		)
		(fp_line
			(start 4.84378 -2.150618)
			(end 4.53898 -2.150618)
			(stroke
				(width 0.1524)
				(type default)
			)
			(layer "B.SilkS")
		)
		(fp_line
			(start 4.84378 -2.150618)
			(end 4.842256 2.163064)
			(stroke
				(width 0.1524)
				(type default)
			)
			(layer "B.SilkS")
		)
		(fp_line
			(start -3.64998 -2.15011)
			(end -3.64998 2.15011)
			(stroke
				(width 0.1)
				(type default)
			)
			(layer "B.Fab")
		)
		(fp_line
			(start -3.64998 2.15011)
			(end 3.64998 2.15011)
			(stroke
				(width 0.1)
				(type default)
			)
			(layer "B.Fab")
		)
		(fp_line
			(start 3.64998 -2.15011)
			(end -3.64998 -2.15011)
			(stroke
				(width 0.1)
				(type default)
			)
			(layer "B.Fab")
		)
		(fp_line
			(start 3.64998 2.15011)
			(end 3.64998 -2.15011)
			(stroke
				(width 0.1)
				(type default)
			)
			(layer "B.Fab")
		)
		(fp_text user "-"
			(at -2.827274 2.572512 0)
			(unlocked yes)
			(layer "B.SilkS")
			(effects
				(font
					(size 1.905 1.4224)
					(thickness 0.1524)
				)
				(justify left mirror)
			)
		)
		(fp_text user "+"
			(at 6.214872 -0.337058 0)
			(unlocked yes)
			(layer "B.SilkS")
			(effects
				(font
					(size 1.905 1.4224)
					(thickness 0.1524)
				)
				(justify left mirror)
			)
		)
		(fp_text user "-"
			(at -4.313174 -0.094488 0)
			(unlocked yes)
			(layer "B.Fab")
			(effects
				(font
					(size 1.905 1.4224)
					(thickness 0.1524)
				)
				(justify left mirror)
			)
		)
		(fp_text user "+"
			(at 6.214872 -0.337058 0)
			(unlocked yes)
			(layer "B.Fab")
			(effects
				(font
					(size 1.905 1.4224)
					(thickness 0.1524)
				)
				(justify left mirror)
			)
		)
		(pad "1" smd rect
			(at 3.199892 0 180)
			(size 2.413 2.8194)
			(layers "B.Cu" "B.Mask" "B.Paste")
			(net "P0V9_CPU1_RT1_2A")
		)
		(pad "2" smd rect
			(at -3.199892 0 180)
			(size 2.413 2.8194)
			(layers "B.Cu" "B.Mask" "B.Paste")
			(net "GND")
		)
	)
	(footprint ""
		(layer "B.Cu")
		(at 128.878584 -386.766562 90)
		(property "Reference" "C453"
			(at 0 0 90)
			(layer "B.SilkS")
			(hide yes)
			(effects
				(font
					(size 1.27 1.27)
				)
				(justify mirror)
			)
		)
		(property "Value" ""
			(at 0 0 90)
			(layer "B.Fab")
			(effects
				(font
					(size 1.27 1.27)
				)
				(justify mirror)
			)
		)
		(duplicate_pad_numbers_are_jumpers no)
		(fp_line
			(start 0.299974 -0.150114)
			(end -0.299974 -0.150114)
			(stroke
				(width 0.1)
				(type default)
			)
			(layer "B.Fab")
		)
		(fp_line
			(start -0.299974 -0.150114)
			(end -0.299974 0.150114)
			(stroke
				(width 0.1)
				(type default)
			)
			(layer "B.Fab")
		)
		(fp_line
			(start 0.299974 0.150114)
			(end 0.299974 -0.150114)
			(stroke
				(width 0.1)
				(type default)
			)
			(layer "B.Fab")
		)
		(fp_line
			(start -0.299974 0.150114)
			(end 0.299974 0.150114)
			(stroke
				(width 0.1)
				(type default)
			)
			(layer "B.Fab")
		)
		(pad "1" smd rect
			(at 0.2667 0 270)
			(size 0.3048 0.381)
			(layers "B.Cu" "B.Mask" "B.Paste")
			(net "P0V9_CPU1_RT3_2A")
		)
		(pad "2" smd rect
			(at -0.2667 0 270)
			(size 0.3048 0.381)
			(layers "B.Cu" "B.Mask" "B.Paste")
			(net "GND")
		)
	)
	(footprint ""
		(layer "B.Cu")
		(at 18.039588 -397.456406)
		(property "Reference" "PC6617_1"
			(at 0 0 0)
			(layer "B.SilkS")
			(hide yes)
			(effects
				(font
					(size 1.27 1.27)
				)
				(justify mirror)
			)
		)
		(property "Value" ""
			(at 0 0 0)
			(layer "B.Fab")
			(effects
				(font
					(size 1.27 1.27)
				)
				(justify mirror)
			)
		)
		(duplicate_pad_numbers_are_jumpers no)
		(fp_line
			(start -1.524 -0.762)
			(end -1.524 0.762)
			(stroke
				(width 0.1524)
				(type default)
			)
			(layer "B.SilkS")
		)
		(fp_line
			(start -1.524 0.762)
			(end 1.524 0.762)
			(stroke
				(width 0.1524)
				(type default)
			)
			(layer "B.SilkS")
		)
		(fp_line
			(start 1.524 -0.762)
			(end -1.524 -0.762)
			(stroke
				(width 0.1524)
				(type default)
			)
			(layer "B.SilkS")
		)
		(fp_line
			(start 1.524 0.762)
			(end 1.524 -0.762)
			(stroke
				(width 0.1524)
				(type default)
			)
			(layer "B.SilkS")
		)
		(fp_line
			(start -1.1049 -0.724916)
			(end 1.1049 -0.724916)
			(stroke
				(width 0.1)
				(type default)
			)
			(layer "B.Fab")
		)
		(fp_line
			(start -1.1049 0.724916)
			(end -1.1049 -0.724916)
			(stroke
				(width 0.1)
				(type default)
			)
			(layer "B.Fab")
		)
		(fp_line
			(start 1.1049 -0.724916)
			(end 1.1049 0.724916)
			(stroke
				(width 0.1)
				(type default)
			)
			(layer "B.Fab")
		)
		(fp_line
			(start 1.1049 0.724916)
			(end -1.1049 0.724916)
			(stroke
				(width 0.1)
				(type default)
			)
			(layer "B.Fab")
		)
		(pad "1" smd rect
			(at 0.889 0)
			(size 1.016 1.27)
			(layers "B.Cu" "B.Mask" "B.Paste")
			(net "SW_P12V_AUX_P0V9_RETIMER_CPU1_FLT")
		)
		(pad "2" smd rect
			(at -0.889 0)
			(size 1.016 1.27)
			(layers "B.Cu" "B.Mask" "B.Paste")
			(net "GND")
		)
	)
	(footprint ""
		(layer "B.Cu")
		(at 424.670474 -351.032826 90)
		(property "Reference" "PC213_1"
			(at 0 0 90)
			(layer "B.SilkS")
			(hide yes)
			(effects
				(font
					(size 1.27 1.27)
				)
				(justify mirror)
			)
		)
		(property "Value" ""
			(at 0 0 90)
			(layer "B.Fab")
			(effects
				(font
					(size 1.27 1.27)
				)
				(justify mirror)
			)
		)
		(duplicate_pad_numbers_are_jumpers no)
		(fp_line
			(start 1.524 -0.762)
			(end -1.524 -0.762)
			(stroke
				(width 0.1524)
				(type default)
			)
			(layer "B.SilkS")
		)
		(fp_line
			(start -1.524 -0.762)
			(end -1.524 0.762)
			(stroke
				(width 0.1524)
				(type default)
			)
			(layer "B.SilkS")
		)
		(fp_line
			(start 1.524 0.762)
			(end 1.524 -0.762)
			(stroke
				(width 0.1524)
				(type default)
			)
			(layer "B.SilkS")
		)
		(fp_line
			(start -1.524 0.762)
			(end 1.524 0.762)
			(stroke
				(width 0.1524)
				(type default)
			)
			(layer "B.SilkS")
		)
		(fp_line
			(start 1.1049 -0.724916)
			(end 1.1049 0.724916)
			(stroke
				(width 0.1)
				(type default)
			)
			(layer "B.Fab")
		)
		(fp_line
			(start -1.1049 -0.724916)
			(end 1.1049 -0.724916)
			(stroke
				(width 0.1)
				(type default)
			)
			(layer "B.Fab")
		)
		(fp_line
			(start 1.1049 0.724916)
			(end -1.1049 0.724916)
			(stroke
				(width 0.1)
				(type default)
			)
			(layer "B.Fab")
		)
		(fp_line
			(start -1.1049 0.724916)
			(end -1.1049 -0.724916)
			(stroke
				(width 0.1)
				(type default)
			)
			(layer "B.Fab")
		)
		(pad "1" smd rect
			(at 0.889 0 90)
			(size 1.016 1.27)
			(layers "B.Cu" "B.Mask" "B.Paste")
			(net "SW_P12V_AUX_PVDD11_S3_P0_FLT")
		)
		(pad "2" smd rect
			(at -0.889 0 90)
			(size 1.016 1.27)
			(layers "B.Cu" "B.Mask" "B.Paste")
			(net "GND")
		)
	)
	(footprint ""
		(layer "B.Cu")
		(at 205.150466 -128.082294 180)
		(property "Reference" "R6823"
			(at 0 0 0)
			(layer "B.SilkS")
			(hide yes)
			(effects
				(font
					(size 1.27 1.27)
				)
				(justify mirror)
			)
		)
		(property "Value" ""
			(at 0 0 0)
			(layer "B.Fab")
			(effects
				(font
					(size 1.27 1.27)
				)
				(justify mirror)
			)
		)
		(duplicate_pad_numbers_are_jumpers no)
		(fp_line
			(start 0.7874 0.4064)
			(end 0.7874 -0.4064)
			(stroke
				(width 0.1524)
				(type default)
			)
			(layer "B.SilkS")
		)
		(fp_line
			(start 0.7874 -0.4064)
			(end -0.7874 -0.4064)
			(stroke
				(width 0.1524)
				(type default)
			)
			(layer "B.SilkS")
		)
		(fp_line
			(start -0.7874 0.4064)
			(end 0.7874 0.4064)
			(stroke
				(width 0.1524)
				(type default)
			)
			(layer "B.SilkS")
		)
		(fp_line
			(start -0.7874 -0.4064)
			(end -0.7874 0.4064)
			(stroke
				(width 0.1524)
				(type default)
			)
			(layer "B.SilkS")
		)
		(fp_line
			(start 0.67945 0.3048)
			(end 0.67945 -0.305054)
			(stroke
				(width 0.1)
				(type default)
			)
			(layer "B.Fab")
		)
		(fp_line
			(start 0.67945 -0.305054)
			(end 0.12065 -0.305054)
			(stroke
				(width 0.1)
				(type default)
			)
			(layer "B.Fab")
		)
		(fp_line
			(start 0.12065 0.3048)
			(end 0.67945 0.3048)
			(stroke
				(width 0.1)
				(type default)
			)
			(layer "B.Fab")
		)
		(fp_line
			(start 0.12065 0.2794)
			(end 0.12065 0.3048)
			(stroke
				(width 0.1)
				(type default)
			)
			(layer "B.Fab")
		)
		(fp_line
			(start 0.12065 -0.2794)
			(end -0.12065 -0.2794)
			(stroke
				(width 0.1)
				(type default)
			)
			(layer "B.Fab")
		)
		(fp_line
			(start 0.12065 -0.305054)
			(end 0.12065 -0.2794)
			(stroke
				(width 0.1)
				(type default)
			)
			(layer "B.Fab")
		)
		(fp_line
			(start -0.120396 0.3048)
			(end -0.120396 0.2794)
			(stroke
				(width 0.1)
				(type default)
			)
			(layer "B.Fab")
		)
		(fp_line
			(start -0.120396 0.2794)
			(end 0.12065 0.2794)
			(stroke
				(width 0.1)
				(type default)
			)
			(layer "B.Fab")
		)
		(fp_line
			(start -0.12065 -0.2794)
			(end -0.12065 -0.3048)
			(stroke
				(width 0.1)
				(type default)
			)
			(layer "B.Fab")
		)
		(fp_line
			(start -0.12065 -0.3048)
			(end -0.67945 -0.3048)
			(stroke
				(width 0.1)
				(type default)
			)
			(layer "B.Fab")
		)
		(fp_line
			(start -0.67945 0.3048)
			(end -0.120396 0.3048)
			(stroke
				(width 0.1)
				(type default)
			)
			(layer "B.Fab")
		)
		(fp_line
			(start -0.67945 -0.3048)
			(end -0.67945 0.3048)
			(stroke
				(width 0.1)
				(type default)
			)
			(layer "B.Fab")
		)
		(pad "1" smd circle
			(at 0.40005 0)
			(size 0 0)
			(layers "B.Cu" "B.Mask" "B.Paste")
			(net "RST_RT_CPU0_P2_PERST_R2_N")
		)
		(pad "2" smd circle
			(at -0.40005 0)
			(size 0 0)
			(layers "B.Cu" "B.Mask" "B.Paste")
			(net "RST_RT_CPU0_P2_PERST_R_N")
		)
	)
	(footprint ""
		(layer "B.Cu")
		(at 388.196836 -178.965098 90)
		(property "Reference" "PC555_4"
			(at 0 0 90)
			(layer "B.SilkS")
			(hide yes)
			(effects
				(font
					(size 1.27 1.27)
				)
				(justify mirror)
			)
		)
		(property "Value" ""
			(at 0 0 90)
			(layer "B.Fab")
			(effects
				(font
					(size 1.27 1.27)
				)
				(justify mirror)
			)
		)
		(duplicate_pad_numbers_are_jumpers no)
		(fp_line
			(start 1.524 -0.762)
			(end -1.524 -0.762)
			(stroke
				(width 0.1524)
				(type default)
			)
			(layer "B.SilkS")
		)
		(fp_line
			(start -1.524 -0.762)
			(end -1.524 0.762)
			(stroke
				(width 0.1524)
				(type default)
			)
			(layer "B.SilkS")
		)
		(fp_line
			(start 1.524 0.762)
			(end 1.524 -0.762)
			(stroke
				(width 0.1524)
				(type default)
			)
			(layer "B.SilkS")
		)
		(fp_line
			(start -1.524 0.762)
			(end 1.524 0.762)
			(stroke
				(width 0.1524)
				(type default)
			)
			(layer "B.SilkS")
		)
		(fp_line
			(start 1.1049 -0.724916)
			(end 1.1049 0.724916)
			(stroke
				(width 0.1)
				(type default)
			)
			(layer "B.Fab")
		)
		(fp_line
			(start -1.1049 -0.724916)
			(end 1.1049 -0.724916)
			(stroke
				(width 0.1)
				(type default)
			)
			(layer "B.Fab")
		)
		(fp_line
			(start 1.1049 0.724916)
			(end -1.1049 0.724916)
			(stroke
				(width 0.1)
				(type default)
			)
			(layer "B.Fab")
		)
		(fp_line
			(start -1.1049 0.724916)
			(end -1.1049 -0.724916)
			(stroke
				(width 0.1)
				(type default)
			)
			(layer "B.Fab")
		)
		(pad "1" smd rect
			(at 0.889 0 90)
			(size 1.016 1.27)
			(layers "B.Cu" "B.Mask" "B.Paste")
			(net "SW_P12V_AUX_PVDDCR_CPU0_P0_FLT")
		)
		(pad "2" smd rect
			(at -0.889 0 90)
			(size 1.016 1.27)
			(layers "B.Cu" "B.Mask" "B.Paste")
			(net "GND")
		)
	)
)
